# S9S_MB_2U (Grand Teton) — schematic netlist excerpt (pin names and nets, part order shuffled) for the footprints in the layout excerpt that follows; sources: Cadence DE-HDL packaged netlist, KiCad conversion of 03242023_DA0F0TMBIJ0_F0T_Motherboard_J_brd_V01_OCP.brd

C2346  Q_CAP  0.1UF 25V 10% X7R  pkg 0402  page 158 : A = P3V3_AUX ; B = GND

(kicad_pcb
	(version 20260206)
	(generator "pcbnew")
	(generator_version "10.0")
	(general
		(thickness 1.6)
		(legacy_teardrops no)
	)
	(paper "A4")
	(title_block
		(title "03242023_DA0F0TMBIJ0_F0T_Motherboard_J_brd_V01_OCP.brd")
		(comment 1 "Grand Teton / footprints 3271-3271 of 6105")
	)
	(layers
		(0 "F.Cu" signal "TOP")
		(4 "In1.Cu" signal "GND")
		(6 "In2.Cu" signal "IN1")
		(8 "In3.Cu" signal "GND1")
		(10 "In4.Cu" signal "IN2")
		(12 "In5.Cu" signal "GND2")
		(14 "In6.Cu" signal "IN3")
		(16 "In7.Cu" signal "GND3")
		(18 "In8.Cu" signal "VCC")
		(20 "In9.Cu" signal "VCC1")
		(22 "In10.Cu" signal "GND4")
		(24 "In11.Cu" signal "IN4")
		(26 "In12.Cu" signal "GND5")
		(28 "In13.Cu" signal "IN5")
		(30 "In14.Cu" signal "GND6")
		(32 "In15.Cu" signal "IN6")
		(34 "In16.Cu" signal "GND7")
		(2 "B.Cu" signal "BOTTOM")
		(9 "F.Adhes" user "F.Adhesive")
		(11 "B.Adhes" user "B.Adhesive")
		(13 "F.Paste" user "Package Geometry/Pastemask Top")
		(15 "B.Paste" user "Package Geometry/Pastemask Bottom")
		(5 "F.SilkS" user "Ref Des/Silkscreen Top")
		(7 "B.SilkS" user "Ref Des/Silkscreen Bottom")
		(1 "F.Mask" user "Board Geometry/Soldermask Top")
		(3 "B.Mask" user "Board Geometry/Soldermask Bottom")
		(17 "Dwgs.User" user "User.Drawings")
		(19 "Cmts.User" user "User.Comments")
		(21 "Eco1.User" user "User.Eco1")
		(23 "Eco2.User" user "User.Eco2")
		(25 "Edge.Cuts" user "Board Geometry/Outline")
		(27 "Margin" user)
		(31 "F.CrtYd" user "Package Geometry/Place Bound Top")
		(29 "B.CrtYd" user "Package Geometry/Place Bound Bottom")
		(35 "F.Fab" user "Ref Des/Assembly Top")
		(33 "B.Fab" user "Ref Des/Assembly Bottom")
	)
	(footprint ""
		(layer "F.Cu")
		(at 385.572 -29.581348)
		(property "Reference" "C2346"
			(at 0 0 0)
			(layer "F.SilkS")
			(hide yes)
			(effects
				(font
					(size 1.27 1.27)
				)
			)
		)
		(property "Value" ""
			(at 0 0 0)
			(layer "F.Fab")
			(effects
				(font
					(size 1.27 1.27)
				)
			)
		)
		(duplicate_pad_numbers_are_jumpers no)
		(fp_line
			(start -0.7874 -0.4064)
			(end 0.7874 -0.4064)
			(stroke
				(width 0.1524)
				(type default)
			)
			(layer "F.SilkS")
		)
		(fp_line
			(start -0.7874 0.4064)
			(end -0.7874 -0.4064)
			(stroke
				(width 0.1524)
				(type default)
			)
			(layer "F.SilkS")
		)
		(fp_line
			(start 0.7874 -0.4064)
			(end 0.7874 0.4064)
			(stroke
				(width 0.1524)
				(type default)
			)
			(layer "F.SilkS")
		)
		(fp_line
			(start 0.7874 0.4064)
			(end -0.7874 0.4064)
			(stroke
				(width 0.1524)
				(type default)
			)
			(layer "F.SilkS")
		)
		(fp_line
			(start -0.67945 -0.305054)
			(end -0.12065 -0.305054)
			(stroke
				(width 0.1)
				(type default)
			)
			(layer "F.Fab")
		)
		(fp_line
			(start -0.67945 0.3048)
			(end -0.67945 -0.305054)
			(stroke
				(width 0.1)
				(type default)
			)
			(layer "F.Fab")
		)
		(fp_line
			(start -0.12065 -0.305054)
			(end -0.12065 -0.2794)
			(stroke
				(width 0.1)
				(type default)
			)
			(layer "F.Fab")
		)
		(fp_line
			(start -0.12065 -0.2794)
			(end 0.12065 -0.2794)
			(stroke
				(width 0.1)
				(type default)
			)
			(layer "F.Fab")
		)
		(fp_line
			(start -0.12065 0.2794)
			(end -0.12065 0.3048)
			(stroke
				(width 0.1)
				(type default)
			)
			(layer "F.Fab")
		)
		(fp_line
			(start -0.12065 0.3048)
			(end -0.67945 0.3048)
			(stroke
				(width 0.1)
				(type default)
			)
			(layer "F.Fab")
		)
		(fp_line
			(start 0.120396 0.2794)
			(end -0.12065 0.2794)
			(stroke
				(width 0.1)
				(type default)
			)
			(layer "F.Fab")
		)
		(fp_line
			(start 0.120396 0.3048)
			(end 0.120396 0.2794)
			(stroke
				(width 0.1)
				(type default)
			)
			(layer "F.Fab")
		)
		(fp_line
			(start 0.12065 -0.3048)
			(end 0.67945 -0.3048)
			(stroke
				(width 0.1)
				(type default)
			)
			(layer "F.Fab")
		)
		(fp_line
			(start 0.12065 -0.2794)
			(end 0.12065 -0.3048)
			(stroke
				(width 0.1)
				(type default)
			)
			(layer "F.Fab")
		)
		(fp_line
			(start 0.67945 -0.3048)
			(end 0.67945 0.3048)
			(stroke
				(width 0.1)
				(type default)
			)
			(layer "F.Fab")
		)
		(fp_line
			(start 0.67945 0.3048)
			(end 0.120396 0.3048)
			(stroke
				(width 0.1)
				(type default)
			)
			(layer "F.Fab")
		)
		(pad "1" smd circle
			(at -0.40005 0)
			(size 0 0)
			(layers "F.Cu" "F.Mask" "F.Paste")
			(net "P3V3_AUX")
		)
		(pad "2" smd circle
			(at 0.40005 0)
			(size 0 0)
			(layers "F.Cu" "F.Mask" "F.Paste")
			(net "GND")
		)
	)
)
